(kicad_pcb
	(version 20260206)
	(generator "pcbnew")
	(generator_version "10.0")
	(general
		(thickness 1.6)
		(legacy_teardrops no)
	)
	(paper "A4")
	(title_block
		(title "Bryce Canyon_R.DPB_16317-1_OCP.brd")
		(comment 1 "Bryce Canyon / footprints 1029-1034 of 2099")
	)
	(layers
		(0 "F.Cu" signal "TOP")
		(4 "In1.Cu" signal "L2GND")
		(6 "In2.Cu" signal "L3")
		(8 "In3.Cu" signal "L4VCC")
		(10 "In4.Cu" signal "L5VCC")
		(12 "In5.Cu" signal "L6")
		(14 "In6.Cu" signal "L7GND")
		(2 "B.Cu" signal "BOTTOM")
		(9 "F.Adhes" user "F.Adhesive")
		(11 "B.Adhes" user "B.Adhesive")
		(13 "F.Paste" user "Package Geometry/Pastemask Top")
		(15 "B.Paste" user "Package Geometry/Pastemask Bottom")
		(5 "F.SilkS" user "Ref Des/Silkscreen Top")
		(7 "B.SilkS" user "Ref Des/Silkscreen Bottom")
		(1 "F.Mask" user "Board Geometry/Soldermask Top")
		(3 "B.Mask" user "Board Geometry/Soldermask Bottom")
		(17 "Dwgs.User" user "User.Drawings")
		(19 "Cmts.User" user "User.Comments")
		(21 "Eco1.User" user "User.Eco1")
		(23 "Eco2.User" user "User.Eco2")
		(25 "Edge.Cuts" user "Board Geometry/Outline")
		(27 "Margin" user)
		(31 "F.CrtYd" user "Package Geometry/Place Bound Top")
		(29 "B.CrtYd" user "Package Geometry/Place Bound Bottom")
		(35 "F.Fab" user "Ref Des/Assembly Top")
		(33 "B.Fab" user "Ref Des/Assembly Bottom")
	)
	(footprint ""
		(layer "F.Cu")
		(at 412.8262 -32.8676 180)
		(property "Reference" "R833"
			(at 0 0 180)
			(layer "F.SilkS")
			(hide yes)
			(effects
				(font
					(size 1.27 1.27)
				)
			)
		)
		(property "Value" "220R3F-1-GP"
			(at -0.0254 -2.5146 180)
			(unlocked yes)
			(layer "F.Fab")
			(hide yes)
			(effects
				(font
					(size 1.016 1.016)
					(thickness 0.1524)
				)
			)
		)
		(property "Device Type" "R603H22"
			(at -0.0254 -4.0386 180)
			(unlocked yes)
			(layer "F.Fab")
			(hide yes)
			(effects
				(font
					(size 1.016 1.016)
					(thickness 0.1524)
				)
			)
		)
		(duplicate_pad_numbers_are_jumpers no)
		(fp_line
			(start 0.2032 0)
			(end 0.4826 0)
			(stroke
				(width 0.2032)
				(type default)
			)
			(layer "F.SilkS")
		)
		(fp_line
			(start -0.4826 0)
			(end -0.2032 0)
			(stroke
				(width 0.2032)
				(type default)
			)
			(layer "F.SilkS")
		)
		(fp_rect
			(start -0.5842 1.3335)
			(end 0.5842 -1.3335)
			(stroke
				(width 0)
				(type default)
			)
			(fill no)
			(layer "F.CrtYd")
		)
		(fp_rect
			(start -0.5842 1.3335)
			(end 0.5842 -1.3335)
			(stroke
				(width 0)
				(type default)
			)
			(fill no)
			(layer "F.Fab")
		)
		(pad "1" smd custom
			(at 0 -0.762 180)
			(size 0.2159 0.2159)
			(layers "F.Cu" "F.Mask" "F.Paste")
			(net "HDD_PRSNT_33")
			(options
				(clearance outline)
				(anchor circle)
			)
			(primitives
				(gr_poly
					(pts
						(arc
							(start -0.3302 -0.4318)
							(mid -0.402042 -0.402042)
							(end -0.4318 -0.3302)
						)
						(arc
							(start -0.4318 0.3302)
							(mid -0.402042 0.402042)
							(end -0.3302 0.4318)
						)
						(arc
							(start 0.3302 0.4318)
							(mid 0.402042 0.402042)
							(end 0.4318 0.3302)
						)
						(arc
							(start 0.4318 -0.3302)
							(mid 0.402042 -0.402042)
							(end 0.3302 -0.4318)
						)
					)
					(width 0)
					(fill yes)
				)
			)
		)
		(pad "2" smd custom
			(at 0 0.762 180)
			(size 0.2159 0.2159)
			(layers "F.Cu" "F.Mask" "F.Paste")
			(net "DRIVE_B_33_INS")
			(options
				(clearance outline)
				(anchor circle)
			)
			(primitives
				(gr_poly
					(pts
						(arc
							(start -0.3302 -0.4318)
							(mid -0.402042 -0.402042)
							(end -0.4318 -0.3302)
						)
						(arc
							(start -0.4318 0.3302)
							(mid -0.402042 0.402042)
							(end -0.3302 0.4318)
						)
						(arc
							(start 0.3302 0.4318)
							(mid 0.402042 0.402042)
							(end 0.4318 0.3302)
						)
						(arc
							(start 0.4318 -0.3302)
							(mid 0.402042 -0.402042)
							(end 0.3302 -0.4318)
						)
					)
					(width 0)
					(fill yes)
				)
			)
		)
	)
	(footprint ""
		(layer "F.Cu")
		(at 213.10346 -164.00526 90)
		(property "Reference" "C12"
			(at 0 0 90)
			(layer "F.SilkS")
			(hide yes)
			(effects
				(font
					(size 1.27 1.27)
				)
			)
		)
		(property "Value" "SCD1U16V2KX-3GP"
			(at 1.1811 -2.7051 90)
			(unlocked yes)
			(layer "F.Fab")
			(hide yes)
			(effects
				(font
					(size 1.016 1.016)
					(thickness 0.1524)
				)
			)
		)
		(property "Device Type" "C402H22"
			(at 1.1811 -4.2291 90)
			(unlocked yes)
			(layer "F.Fab")
			(hide yes)
			(effects
				(font
					(size 1.016 1.016)
					(thickness 0.1524)
				)
			)
		)
		(duplicate_pad_numbers_are_jumpers no)
		(fp_rect
			(start -0.4318 0.9525)
			(end 0.4318 -0.9525)
			(stroke
				(width 0)
				(type default)
			)
			(fill no)
			(layer "F.CrtYd")
		)
		(fp_rect
			(start -0.4318 0.9525)
			(end 0.4318 -0.9525)
			(stroke
				(width 0)
				(type default)
			)
			(fill no)
			(layer "F.Fab")
		)
		(pad "1" smd custom
			(at 0 -0.4445 90)
			(size 0.1524 0.1524)
			(layers "F.Cu" "F.Mask" "F.Paste")
			(net "P3V3_STBY_B")
			(options
				(clearance outline)
				(anchor circle)
			)
			(primitives
				(gr_poly
					(pts
						(arc
							(start 0.3048 -0.2032)
							(mid 0.275042 -0.275042)
							(end 0.2032 -0.3048)
						)
						(arc
							(start -0.2032 -0.3048)
							(mid -0.275042 -0.275042)
							(end -0.3048 -0.2032)
						)
						(arc
							(start -0.3048 0.2032)
							(mid -0.275042 0.275042)
							(end -0.2032 0.3048)
						)
						(arc
							(start 0.2032 0.3048)
							(mid 0.275042 0.275042)
							(end 0.3048 0.2032)
						)
					)
					(width 0)
					(fill yes)
				)
			)
		)
		(pad "2" smd custom
			(at 0 0.4445 90)
			(size 0.1524 0.1524)
			(layers "F.Cu" "F.Mask" "F.Paste")
			(net "GND")
			(options
				(clearance outline)
				(anchor circle)
			)
			(primitives
				(gr_poly
					(pts
						(arc
							(start 0.3048 -0.2032)
							(mid 0.275042 -0.275042)
							(end 0.2032 -0.3048)
						)
						(arc
							(start -0.2032 -0.3048)
							(mid -0.275042 -0.275042)
							(end -0.3048 -0.2032)
						)
						(arc
							(start -0.3048 0.2032)
							(mid -0.275042 0.275042)
							(end -0.2032 0.3048)
						)
						(arc
							(start 0.2032 0.3048)
							(mid 0.275042 0.275042)
							(end 0.3048 0.2032)
						)
					)
					(width 0)
					(fill yes)
				)
			)
		)
	)
	(footprint ""
		(layer "F.Cu")
		(at 459.83017 -228.351842 -90)
		(property "Reference" "R1142"
			(at 0 0 270)
			(layer "F.SilkS")
			(hide yes)
			(effects
				(font
					(size 1.27 1.27)
				)
			)
		)
		(property "Value" "15KR2F-GP"
			(at 0.064008 -3.993896 270)
			(unlocked yes)
			(layer "F.Fab")
			(hide yes)
			(effects
				(font
					(size 1.016 1.016)
					(thickness 0.1524)
				)
			)
		)
		(property "Device Type" "R402H16"
			(at 0.064008 -5.517896 270)
			(unlocked yes)
			(layer "F.Fab")
			(hide yes)
			(effects
				(font
					(size 1.016 1.016)
					(thickness 0.1524)
				)
			)
		)
		(duplicate_pad_numbers_are_jumpers no)
		(fp_line
			(start -0.508 -0.9398)
			(end -0.508 0.9398)
			(stroke
				(width 0.1524)
				(type default)
			)
			(layer "F.SilkS")
		)
		(fp_line
			(start 0.508 -0.9398)
			(end -0.508 -0.9398)
			(stroke
				(width 0.1524)
				(type default)
			)
			(layer "F.SilkS")
		)
		(fp_rect
			(start -0.508 0.9398)
			(end 0.508 -0.9398)
			(stroke
				(width 0)
				(type default)
			)
			(fill no)
			(layer "F.CrtYd")
		)
		(fp_rect
			(start -0.508 0.9398)
			(end 0.508 -0.9398)
			(stroke
				(width 0)
				(type default)
			)
			(fill no)
			(layer "F.Fab")
		)
		(pad "1" smd custom
			(at 0 -0.4445 270)
			(size 0.1397 0.1397)
			(layers "F.Cu" "F.Mask" "F.Paste")
			(net "P5V_B_3_PGOOD")
			(options
				(clearance outline)
				(anchor circle)
			)
			(primitives
				(gr_poly
					(pts
						(arc
							(start -0.1778 -0.2794)
							(mid -0.249642 -0.249642)
							(end -0.2794 -0.1778)
						)
						(arc
							(start -0.2794 0.1778)
							(mid -0.249642 0.249642)
							(end -0.1778 0.2794)
						)
						(arc
							(start 0.1778 0.2794)
							(mid 0.249642 0.249642)
							(end 0.2794 0.1778)
						)
						(arc
							(start 0.2794 -0.1778)
							(mid 0.249642 -0.249642)
							(end 0.1778 -0.2794)
						)
					)
					(width 0)
					(fill yes)
				)
			)
		)
		(pad "2" smd custom
			(at 0 0.4445 270)
			(size 0.1397 0.1397)
			(layers "F.Cu" "F.Mask" "F.Paste")
			(net "GND")
			(options
				(clearance outline)
				(anchor circle)
			)
			(primitives
				(gr_poly
					(pts
						(arc
							(start -0.1778 -0.2794)
							(mid -0.249642 -0.249642)
							(end -0.2794 -0.1778)
						)
						(arc
							(start -0.2794 0.1778)
							(mid -0.249642 0.249642)
							(end -0.1778 0.2794)
						)
						(arc
							(start 0.1778 0.2794)
							(mid 0.249642 0.249642)
							(end 0.2794 0.1778)
						)
						(arc
							(start 0.2794 -0.1778)
							(mid 0.249642 -0.249642)
							(end 0.1778 -0.2794)
						)
					)
					(width 0)
					(fill yes)
				)
			)
		)
	)
	(footprint ""
		(layer "F.Cu")
		(at 401.828 -258.826 90)
		(property "Reference" "C143"
			(at 0 0 90)
			(layer "F.SilkS")
			(hide yes)
			(effects
				(font
					(size 1.27 1.27)
				)
			)
		)
		(property "Value" "SCD033U25V2KX-GP"
			(at 1.1811 -2.7051 90)
			(unlocked yes)
			(layer "F.Fab")
			(hide yes)
			(effects
				(font
					(size 1.016 1.016)
					(thickness 0.1524)
				)
			)
		)
		(property "Device Type" "C402H22"
			(at 1.1811 -4.2291 90)
			(unlocked yes)
			(layer "F.Fab")
			(hide yes)
			(effects
				(font
					(size 1.016 1.016)
					(thickness 0.1524)
				)
			)
		)
		(duplicate_pad_numbers_are_jumpers no)
		(fp_rect
			(start -0.4318 0.9525)
			(end 0.4318 -0.9525)
			(stroke
				(width 0)
				(type default)
			)
			(fill no)
			(layer "F.CrtYd")
		)
		(fp_rect
			(start -0.4318 0.9525)
			(end 0.4318 -0.9525)
			(stroke
				(width 0)
				(type default)
			)
			(fill no)
			(layer "F.Fab")
		)
		(pad "1" smd custom
			(at 0 -0.4445 90)
			(size 0.1524 0.1524)
			(layers "F.Cu" "F.Mask" "F.Paste")
			(net "P12V_B")
			(options
				(clearance outline)
				(anchor circle)
			)
			(primitives
				(gr_poly
					(pts
						(arc
							(start 0.3048 -0.2032)
							(mid 0.275042 -0.275042)
							(end 0.2032 -0.3048)
						)
						(arc
							(start -0.2032 -0.3048)
							(mid -0.275042 -0.275042)
							(end -0.3048 -0.2032)
						)
						(arc
							(start -0.3048 0.2032)
							(mid -0.275042 0.275042)
							(end -0.2032 0.3048)
						)
						(arc
							(start 0.2032 0.3048)
							(mid 0.275042 0.275042)
							(end 0.3048 0.2032)
						)
					)
					(width 0)
					(fill yes)
				)
			)
		)
		(pad "2" smd custom
			(at 0 0.4445 90)
			(size 0.1524 0.1524)
			(layers "F.Cu" "F.Mask" "F.Paste")
			(net "SW_HDD_N8")
			(options
				(clearance outline)
				(anchor circle)
			)
			(primitives
				(gr_poly
					(pts
						(arc
							(start 0.3048 -0.2032)
							(mid 0.275042 -0.275042)
							(end 0.2032 -0.3048)
						)
						(arc
							(start -0.2032 -0.3048)
							(mid -0.275042 -0.275042)
							(end -0.3048 -0.2032)
						)
						(arc
							(start -0.3048 0.2032)
							(mid -0.275042 0.275042)
							(end -0.2032 0.3048)
						)
						(arc
							(start 0.2032 0.3048)
							(mid 0.275042 0.275042)
							(end 0.3048 0.2032)
						)
					)
					(width 0)
					(fill yes)
				)
			)
		)
	)
	(footprint ""
		(layer "F.Cu")
		(at 320.465196 -377.1646 90)
		(property "Reference" "R181"
			(at 0 0 90)
			(layer "F.SilkS")
			(hide yes)
			(effects
				(font
					(size 1.27 1.27)
				)
			)
		)
		(property "Value" "4K7R2F-GP"
			(at 0.064008 -3.993896 90)
			(unlocked yes)
			(layer "F.Fab")
			(hide yes)
			(effects
				(font
					(size 1.016 1.016)
					(thickness 0.1524)
				)
			)
		)
		(property "Device Type" "R402H16"
			(at 0.064008 -5.517896 90)
			(unlocked yes)
			(layer "F.Fab")
			(hide yes)
			(effects
				(font
					(size 1.016 1.016)
					(thickness 0.1524)
				)
			)
		)
		(duplicate_pad_numbers_are_jumpers no)
		(fp_line
			(start 0.508 -0.9398)
			(end -0.508 -0.9398)
			(stroke
				(width 0.1524)
				(type default)
			)
			(layer "F.SilkS")
		)
		(fp_line
			(start -0.508 -0.9398)
			(end -0.508 0.9398)
			(stroke
				(width 0.1524)
				(type default)
			)
			(layer "F.SilkS")
		)
		(fp_rect
			(start -0.508 0.9398)
			(end 0.508 -0.9398)
			(stroke
				(width 0)
				(type default)
			)
			(fill no)
			(layer "F.CrtYd")
		)
		(fp_rect
			(start -0.508 0.9398)
			(end 0.508 -0.9398)
			(stroke
				(width 0)
				(type default)
			)
			(fill no)
			(layer "F.Fab")
		)
		(pad "1" smd custom
			(at 0 -0.4445 90)
			(size 0.1397 0.1397)
			(layers "F.Cu" "F.Mask" "F.Paste")
			(net "FAN_BLUE_LED2")
			(options
				(clearance outline)
				(anchor circle)
			)
			(primitives
				(gr_poly
					(pts
						(arc
							(start -0.1778 -0.2794)
							(mid -0.249642 -0.249642)
							(end -0.2794 -0.1778)
						)
						(arc
							(start -0.2794 0.1778)
							(mid -0.249642 0.249642)
							(end -0.1778 0.2794)
						)
						(arc
							(start 0.1778 0.2794)
							(mid 0.249642 0.249642)
							(end 0.2794 0.1778)
						)
						(arc
							(start 0.2794 -0.1778)
							(mid 0.249642 -0.249642)
							(end 0.1778 -0.2794)
						)
					)
					(width 0)
					(fill yes)
				)
			)
		)
		(pad "2" smd custom
			(at 0 0.4445 90)
			(size 0.1397 0.1397)
			(layers "F.Cu" "F.Mask" "F.Paste")
			(net "P12V_IN")
			(options
				(clearance outline)
				(anchor circle)
			)
			(primitives
				(gr_poly
					(pts
						(arc
							(start -0.1778 -0.2794)
							(mid -0.249642 -0.249642)
							(end -0.2794 -0.1778)
						)
						(arc
							(start -0.2794 0.1778)
							(mid -0.249642 0.249642)
							(end -0.1778 0.2794)
						)
						(arc
							(start 0.1778 0.2794)
							(mid 0.249642 0.249642)
							(end 0.2794 0.1778)
						)
						(arc
							(start 0.2794 -0.1778)
							(mid 0.249642 -0.249642)
							(end 0.1778 -0.2794)
						)
					)
					(width 0)
					(fill yes)
				)
			)
		)
	)
	(footprint ""
		(layer "F.Cu")
		(at 401.193 -135.509 90)
		(property "Reference" "R546"
			(at 0 0 90)
			(layer "F.SilkS")
			(hide yes)
			(effects
				(font
					(size 1.27 1.27)
				)
			)
		)
		(property "Value" "200KR2F-L-GP"
			(at 0.064008 -3.993896 90)
			(unlocked yes)
			(layer "F.Fab")
			(hide yes)
			(effects
				(font
					(size 1.016 1.016)
					(thickness 0.1524)
				)
			)
		)
		(property "Device Type" "R402H16"
			(at 0.064008 -5.517896 90)
			(unlocked yes)
			(layer "F.Fab")
			(hide yes)
			(effects
				(font
					(size 1.016 1.016)
					(thickness 0.1524)
				)
			)
		)
		(duplicate_pad_numbers_are_jumpers no)
		(fp_line
			(start 0.508 -0.9398)
			(end -0.508 -0.9398)
			(stroke
				(width 0.1524)
				(type default)
			)
			(layer "F.SilkS")
		)
		(fp_line
			(start -0.508 -0.9398)
			(end -0.508 0.9398)
			(stroke
				(width 0.1524)
				(type default)
			)
			(layer "F.SilkS")
		)
		(fp_rect
			(start -0.508 0.9398)
			(end 0.508 -0.9398)
			(stroke
				(width 0)
				(type default)
			)
			(fill no)
			(layer "F.CrtYd")
		)
		(fp_rect
			(start -0.508 0.9398)
			(end 0.508 -0.9398)
			(stroke
				(width 0)
				(type default)
			)
			(fill no)
			(layer "F.Fab")
		)
		(pad "1" smd custom
			(at 0 -0.4445 90)
			(size 0.1397 0.1397)
			(layers "F.Cu" "F.Mask" "F.Paste")
			(net "SW_HDD_R20")
			(options
				(clearance outline)
				(anchor circle)
			)
			(primitives
				(gr_poly
					(pts
						(arc
							(start -0.1778 -0.2794)
							(mid -0.249642 -0.249642)
							(end -0.2794 -0.1778)
						)
						(arc
							(start -0.2794 0.1778)
							(mid -0.249642 0.249642)
							(end -0.1778 0.2794)
						)
						(arc
							(start 0.1778 0.2794)
							(mid 0.249642 0.249642)
							(end 0.2794 0.1778)
						)
						(arc
							(start 0.2794 -0.1778)
							(mid 0.249642 -0.249642)
							(end 0.1778 -0.2794)
						)
					)
					(width 0)
					(fill yes)
				)
			)
		)
		(pad "2" smd custom
			(at 0 0.4445 90)
			(size 0.1397 0.1397)
			(layers "F.Cu" "F.Mask" "F.Paste")
			(net "SW_HDD_N20")
			(options
				(clearance outline)
				(anchor circle)
			)
			(primitives
				(gr_poly
					(pts
						(arc
							(start -0.1778 -0.2794)
							(mid -0.249642 -0.249642)
							(end -0.2794 -0.1778)
						)
						(arc
							(start -0.2794 0.1778)
							(mid -0.249642 0.249642)
							(end -0.1778 0.2794)
						)
						(arc
							(start 0.1778 0.2794)
							(mid 0.249642 0.249642)
							(end 0.2794 0.1778)
						)
						(arc
							(start 0.2794 -0.1778)
							(mid 0.249642 -0.249642)
							(end 0.1778 -0.2794)
						)
					)
					(width 0)
					(fill yes)
				)
			)
		)
	)
)
